(kicad_pcb
	(version 20221018)
	(generator pcbnew)
	(general
    (thickness 1.518)
  )
	(paper "A4")
	(title_block
    (title "Kria K26 Devboard")
    (date "2024-03-26")
    (rev "1.2.5")
    (comment 1 "www.antmicro.com")
    (comment 2 "Antmicro Ltd.")
		(comment 9 "footprints 41-48 of 660")
	)
	(layers
    (0 "F.Cu" mixed)
    (1 "In1.Cu" power)
    (2 "In2.Cu" mixed)
    (3 "In3.Cu" power)
    (4 "In4.Cu" mixed)
    (5 "In5.Cu" power)
    (6 "In6.Cu" mixed)
    (31 "B.Cu" power)
    (32 "B.Adhes" user "B.Adhesive")
    (33 "F.Adhes" user "F.Adhesive")
    (34 "B.Paste" user)
    (35 "F.Paste" user)
    (36 "B.SilkS" user "B.Silkscreen")
    (37 "F.SilkS" user "F.Silkscreen")
    (38 "B.Mask" user)
    (39 "F.Mask" user)
    (40 "Dwgs.User" user "User.Drawings")
    (41 "Cmts.User" user "User.Comments")
    (42 "Eco1.User" user "User.Eco1")
    (43 "Eco2.User" user "User.Eco2")
    (44 "Edge.Cuts" user)
    (45 "Margin" user)
    (46 "B.CrtYd" user "B.Courtyard")
    (47 "F.CrtYd" user "F.Courtyard")
    (48 "B.Fab" user)
    (49 "F.Fab" user)
  )
	(footprint "kria-k26-devboard-footprints:antmicro-logo"
		(layer "F.Cu")
    (at 91.1 78.779847)
    (property "Author" "Antmicro")
    (property "License" "Apache-2.0")
    (property "MPN" "")
    (property "Manufacturer" "")
    (property "Sheetfile" "kria-k26-devboard.kicad_sch")
    (property "Sheetname" "")
    (attr exclude_from_pos_files)
    (fp_text reference "N1" (at -7.7 -10.3) (layer "F.SilkS") hide
        (effects (font (size 1.524 1.524) (thickness 0.3)))
    )
    (fp_text value "antmicro_logo" (at -5.3 10.1) (layer "F.SilkS") hide
        (effects (font (size 1.524 1.524) (thickness 0.3)))
    )
  )
	(footprint "kria-k26-devboard-footprints:C_0402_1005Metric" (layer "F.Cu")
    (at 84.38 71.317 90)
    (descr "Capacitor SMD 0402")
    (tags "capacitor SMD 0402")
    (property "Author" "Antmicro")
    (property "Dielectric" "X5R")
    (property "License" "Apache-2.0")
    (property "MPN" "GRM155R61H104KE14D")
    (property "Manufacturer" "Murata")
    (property "Sheetfile" "dp.kicad_sch")
    (property "Sheetname" "Display Port")
    (property "Val" "100n")
    (property "Voltage" "50V")
    (property "ki_description" " ")
    (attr smd)
    (fp_text reference "C6" (at -2.403 0.37 90) (layer "F.SilkS")
        (effects (font (size 0.7 0.7) (thickness 0.15)) (justify left bottom))
    )
    (fp_text value "C_100n_0402" (at 0 1.4 90) (layer "F.Fab") hide
        (effects (font (size 0.7 0.7) (thickness 0.15)) (justify left bottom))
    )
    (fp_text user "${REFERENCE}" (at -0.932 3.168 90) (layer "F.Fab") hide
        (effects (font (size 0.7 0.7) (thickness 0.15)) (justify left bottom))
    )
    (fp_text user "Author: Antmicro" (at -0.932 4.17 90) (layer "F.Fab") hide
        (effects (font (size 0.7 0.7) (thickness 0.15)) (justify left bottom))
    )
    (fp_text user "License: Apache-2.0" (at -0.932 5.17 90) (layer "F.Fab") hide
        (effects (font (size 0.7 0.7) (thickness 0.15)) (justify left bottom))
    )
    (fp_rect (start -0.94 -0.47) (end 0.94 0.47)
      (stroke (width 0.05) (type solid)) (fill none) (layer "F.CrtYd"))
    (fp_rect (start -0.499 -0.249) (end 0.499 0.249)
      (stroke (width 0.15) (type solid)) (fill none) (layer "F.Fab"))
    (pad "1" smd roundrect (at -0.484 0 90) (size 0.59 0.64) (layers "F.Cu" "F.Paste" "F.Mask") (roundrect_rratio 0.25)
      (net 92 "/Display Port/GTR_DP1_M2C_P") (pintype "passive"))
    (pad "2" smd roundrect (at 0.484 0 90) (size 0.59 0.64) (layers "F.Cu" "F.Paste" "F.Mask") (roundrect_rratio 0.25)
      (net 93 "/Display Port/GTR_DP1_M2C_C_P") (pintype "passive"))
  )
	(footprint "kria-k26-devboard-footprints:C_0402_1005Metric" (layer "F.Cu")
    (at 85.36 71.317 90)
    (descr "Capacitor SMD 0402")
    (tags "capacitor SMD 0402")
    (property "Author" "Antmicro")
    (property "Dielectric" "X5R")
    (property "License" "Apache-2.0")
    (property "MPN" "GRM155R61H104KE14D")
    (property "Manufacturer" "Murata")
    (property "Sheetfile" "dp.kicad_sch")
    (property "Sheetname" "Display Port")
    (property "Val" "100n")
    (property "Voltage" "50V")
    (property "ki_description" " ")
    (attr smd)
    (fp_text reference "C7" (at -2.403 0.37 90) (layer "F.SilkS")
        (effects (font (size 0.7 0.7) (thickness 0.15)) (justify left bottom))
    )
    (fp_text value "C_100n_0402" (at 0 1.4 90) (layer "F.Fab") hide
        (effects (font (size 0.7 0.7) (thickness 0.15)) (justify left bottom))
    )
    (fp_text user "Author: Antmicro" (at -0.932 4.17 90) (layer "F.Fab") hide
        (effects (font (size 0.7 0.7) (thickness 0.15)) (justify left bottom))
    )
    (fp_text user "License: Apache-2.0" (at -0.932 5.17 90) (layer "F.Fab") hide
        (effects (font (size 0.7 0.7) (thickness 0.15)) (justify left bottom))
    )
    (fp_text user "${REFERENCE}" (at -0.932 3.168 90) (layer "F.Fab") hide
        (effects (font (size 0.7 0.7) (thickness 0.15)) (justify left bottom))
    )
    (fp_rect (start -0.94 -0.47) (end 0.94 0.47)
      (stroke (width 0.05) (type solid)) (fill none) (layer "F.CrtYd"))
    (fp_rect (start -0.499 -0.249) (end 0.499 0.249)
      (stroke (width 0.15) (type solid)) (fill none) (layer "F.Fab"))
    (pad "1" smd roundrect (at -0.484 0 90) (size 0.59 0.64) (layers "F.Cu" "F.Paste" "F.Mask") (roundrect_rratio 0.25)
      (net 94 "/Display Port/GTR_DP1_M2C_N") (pintype "passive"))
    (pad "2" smd roundrect (at 0.484 0 90) (size 0.59 0.64) (layers "F.Cu" "F.Paste" "F.Mask") (roundrect_rratio 0.25)
      (net 95 "/Display Port/GTR_DP1_M2C_C_N") (pintype "passive"))
  )
	(footprint "kria-k26-devboard-footprints:D_SOD-323F" (layer "F.Cu")
    (at 95.85 68.99 -90)
    (property "Author" "Antmicro")
    (property "License" "Apache-2.0")
    (property "MPN" "PMEG3010CEJ")
    (property "Manufacturer" "Nexperia")
    (property "Sheetfile" "dp.kicad_sch")
    (property "Sheetname" "Display Port")
    (property "ki_description" "1 A very low V F MEGA Schottky barrier rectifiers")
    (property "ki_keywords" "1 A very low V F MEGA Schottky barrier rectifiers")
    (attr smd)
    (fp_text reference "D1" (at 0.79 -5.2 -90) (layer "F.SilkS")
        (effects (font (size 0.7 0.7) (thickness 0.15)) (justify left bottom))
    )
    (fp_text value "PMEG3010CE_SOD323" (at -1.7 1.9 -90) (layer "F.Fab") hide
        (effects (font (size 0.7 0.7) (thickness 0.15)) (justify left bottom))
    )
    (fp_text user "Author: Antmicro" (at -1.8 4.46 -90) (layer "F.Fab") hide
        (effects (font (size 0.7 0.7) (thickness 0.15)) (justify left bottom))
    )
    (fp_text user "${REFERENCE}" (at -1.8 3.2 -90) (layer "F.Fab") hide
        (effects (font (size 0.7 0.7) (thickness 0.15)) (justify left bottom))
    )
    (fp_text user "License: Apache-2.0" (at -1.8 5.8 -90) (layer "F.Fab") hide
        (effects (font (size 0.7 0.7) (thickness 0.15)) (justify left bottom))
    )
    (fp_line (start -0.975 -0.75) (end -0.975 -0.45)
      (stroke (width 0.15) (type solid)) (layer "F.SilkS"))
    (fp_line (start -0.975 0.748) (end -0.975 0.45)
      (stroke (width 0.15) (type solid)) (layer "F.SilkS"))
    (fp_line (start -0.625 -0.75) (end -0.975 -0.75)
      (stroke (width 0.15) (type solid)) (layer "F.SilkS"))
    (fp_line (start -0.625 0.748) (end -0.975 0.748)
      (stroke (width 0.15) (type solid)) (layer "F.SilkS"))
    (fp_line (start -0.5 -0.426) (end -0.5 0.424)
      (stroke (width 0.15) (type solid)) (layer "F.SilkS"))
    (fp_line (start 0.623 -0.75) (end 0.973 -0.75)
      (stroke (width 0.15) (type solid)) (layer "F.SilkS"))
    (fp_line (start 0.973 -0.75) (end 0.973 -0.45)
      (stroke (width 0.15) (type solid)) (layer "F.SilkS"))
    (fp_line (start 0.973 0.45) (end 0.973 0.748)
      (stroke (width 0.15) (type solid)) (layer "F.SilkS"))
    (fp_line (start 0.973 0.748) (end 0.623 0.748)
      (stroke (width 0.15) (type solid)) (layer "F.SilkS"))
    (fp_rect (start -1.6 -0.827) (end 1.599 0.825)
      (stroke (width 0.05) (type solid)) (fill none) (layer "F.CrtYd"))
    (fp_line (start -0.85 -0.625) (end 0.848 -0.625)
      (stroke (width 0.15) (type solid)) (layer "F.Fab"))
    (fp_line (start -0.85 0.623) (end -0.85 -0.625)
      (stroke (width 0.15) (type solid)) (layer "F.Fab"))
    (fp_line (start -0.85 0.623) (end 0.848 0.623)
      (stroke (width 0.15) (type solid)) (layer "F.Fab"))
    (fp_line (start 0.848 -0.625) (end 0.848 0.623)
      (stroke (width 0.15) (type solid)) (layer "F.Fab"))
    (pad "A" smd roundrect (at 1.05 0 270) (size 0.8 0.6) (layers "F.Cu" "F.Paste" "F.Mask") (roundrect_rratio 0.15)
      (net 15 "PS_3V3") (pinfunction "A") (pintype "passive"))
    (pad "K" smd roundrect (at -1.051 0 270) (size 0.8 0.6) (layers "F.Cu" "F.Paste" "F.Mask") (roundrect_rratio 0.15)
      (net 334 "Net-(J1-DP_PWR)") (pinfunction "K") (pintype "passive"))
  )
	(footprint "kria-k26-devboard-footprints:R_0402_1005Metric" (layer "F.Cu")
    (at 89.75 68.42 -90)
    (descr "Resistor SMD 0402")
    (tags "resistor SMD 0402")
    (property "Author" "Antmicro")
    (property "License" "Apache-2.0")
    (property "MPN" "CR0402-FX-1004GLF")
    (property "Manufacturer" "Bourns")
    (property "Sheetfile" "dp.kicad_sch")
    (property "Sheetname" "Display Port")
    (property "Tolerance" "1%")
    (property "Val" "1M")
    (property "ki_description" "1M resistor in 0402 package with 1% tolerance")
    (attr smd)
    (fp_text reference "R9" (at 1.05 0.56 -90) (layer "F.SilkS")
        (effects (font (size 0.7 0.7) (thickness 0.15)) (justify left bottom))
    )
    (fp_text value "R_1M_0402" (at 0 1.4 -90) (layer "F.Fab") hide
        (effects (font (size 0.7 0.7) (thickness 0.15)) (justify left bottom))
    )
    (fp_text user "License: Apache-2.0" (at -0.95 5.169 -90) (layer "F.Fab") hide
        (effects (font (size 0.7 0.7) (thickness 0.15)) (justify left bottom))
    )
    (fp_text user "${REFERENCE}" (at -0.95 3.168 -90) (layer "F.Fab") hide
        (effects (font (size 0.7 0.7) (thickness 0.15)) (justify left bottom))
    )
    (fp_text user "Author: Antmicro" (at -0.95 4.169 -90) (layer "F.Fab") hide
        (effects (font (size 0.7 0.7) (thickness 0.15)) (justify left bottom))
    )
    (fp_rect (start -0.93 -0.47) (end 0.93 0.47)
      (stroke (width 0.05) (type solid)) (fill none) (layer "F.CrtYd"))
    (fp_rect (start -0.5 -0.25) (end 0.5 0.25)
      (stroke (width 0.15) (type solid)) (fill none) (layer "F.Fab"))
    (pad "1" smd roundrect (at -0.485 0 270) (size 0.59 0.64) (layers "F.Cu" "F.Paste" "F.Mask") (roundrect_rratio 0.25)
      (net 348 "Net-(J1-CFG1)") (pintype "passive"))
    (pad "2" smd roundrect (at 0.485 0 270) (size 0.59 0.64) (layers "F.Cu" "F.Paste" "F.Mask") (roundrect_rratio 0.25)
      (net 1 "GND") (pintype "passive"))
  )
	(footprint "kria-k26-devboard-footprints:R_0402_1005Metric" (layer "F.Cu")
    (at 94.4 68.41 -90)
    (descr "Resistor SMD 0402")
    (tags "resistor SMD 0402")
    (property "Author" "Antmicro")
    (property "Current" "1A")
    (property "License" "Apache-2.0")
    (property "MPN" "ERJ2GE0R00X")
    (property "Manufacturer" "Panasonic")
    (property "Sheetfile" "dp.kicad_sch")
    (property "Sheetname" "Display Port")
    (property "Tolerance" "")
    (property "Val" "0R")
    (property "ki_description" "0R resistor in 0402 package with unspecified tolerance")
    (attr smd)
    (fp_text reference "R10" (at 1.13 -5.29 -90) (layer "F.SilkS")
        (effects (font (size 0.7 0.7) (thickness 0.15)) (justify left bottom))
    )
    (fp_text value "R_0R_0402" (at 0 1.4 -90) (layer "F.Fab") hide
        (effects (font (size 0.7 0.7) (thickness 0.15)) (justify left bottom))
    )
    (fp_text user "Author: Antmicro" (at -0.95 4.169 -90) (layer "F.Fab") hide
        (effects (font (size 0.7 0.7) (thickness 0.15)) (justify left bottom))
    )
    (fp_text user "${REFERENCE}" (at -0.95 3.168 -90) (layer "F.Fab") hide
        (effects (font (size 0.7 0.7) (thickness 0.15)) (justify left bottom))
    )
    (fp_text user "License: Apache-2.0" (at -0.95 5.169 -90) (layer "F.Fab") hide
        (effects (font (size 0.7 0.7) (thickness 0.15)) (justify left bottom))
    )
    (fp_rect (start -0.93 -0.47) (end 0.93 0.47)
      (stroke (width 0.05) (type solid)) (fill none) (layer "F.CrtYd"))
    (fp_rect (start -0.5 -0.25) (end 0.5 0.25)
      (stroke (width 0.15) (type solid)) (fill none) (layer "F.Fab"))
    (pad "1" smd roundrect (at -0.485 0 270) (size 0.59 0.64) (layers "F.Cu" "F.Paste" "F.Mask") (roundrect_rratio 0.25)
      (net 804 "Net-(J1-RTN)") (pintype "passive"))
    (pad "2" smd roundrect (at 0.485 0 270) (size 0.59 0.64) (layers "F.Cu" "F.Paste" "F.Mask") (roundrect_rratio 0.25)
      (net 1 "GND") (pintype "passive"))
  )
	(footprint "kria-k26-devboard-footprints:R_0402_1005Metric" (layer "F.Cu")
    (at 93.43 68.39 -90)
    (descr "Resistor SMD 0402")
    (tags "resistor SMD 0402")
    (property "Author" "Antmicro")
    (property "License" "Apache-2.0")
    (property "MPN" "CR0402-FX-1003GLF")
    (property "Manufacturer" "Bourns")
    (property "Sheetfile" "dp.kicad_sch")
    (property "Sheetname" "Display Port")
    (property "Tolerance" "1%")
    (property "Val" "100k")
    (property "ki_description" "100k resistor in 0402 package with 1% tolerance")
    (attr smd)
    (fp_text reference "R11" (at 1.13 -5.29 -90) (layer "F.SilkS")
        (effects (font (size 0.7 0.7) (thickness 0.15)) (justify left bottom))
    )
    (fp_text value "R_100k_0402" (at 0 1.4 -90) (layer "F.Fab") hide
        (effects (font (size 0.7 0.7) (thickness 0.15)) (justify left bottom))
    )
    (fp_text user "Author: Antmicro" (at -0.95 4.169 -90) (layer "F.Fab") hide
        (effects (font (size 0.7 0.7) (thickness 0.15)) (justify left bottom))
    )
    (fp_text user "License: Apache-2.0" (at -0.95 5.169 -90) (layer "F.Fab") hide
        (effects (font (size 0.7 0.7) (thickness 0.15)) (justify left bottom))
    )
    (fp_text user "${REFERENCE}" (at -0.95 3.168 -90) (layer "F.Fab") hide
        (effects (font (size 0.7 0.7) (thickness 0.15)) (justify left bottom))
    )
    (fp_rect (start -0.93 -0.47) (end 0.93 0.47)
      (stroke (width 0.05) (type solid)) (fill none) (layer "F.CrtYd"))
    (fp_rect (start -0.5 -0.25) (end 0.5 0.25)
      (stroke (width 0.15) (type solid)) (fill none) (layer "F.Fab"))
    (pad "1" smd roundrect (at -0.485 0 270) (size 0.59 0.64) (layers "F.Cu" "F.Paste" "F.Mask") (roundrect_rratio 0.25)
      (net 105 "/Display Port/DP_HPD") (pintype "passive"))
    (pad "2" smd roundrect (at 0.485 0 270) (size 0.59 0.64) (layers "F.Cu" "F.Paste" "F.Mask") (roundrect_rratio 0.25)
      (net 1 "GND") (pintype "passive"))
  )
	(footprint "kria-k26-devboard-footprints:R_0402_1005Metric" (layer "F.Cu")
    (at 90.72 68.42 90)
    (descr "Resistor SMD 0402")
    (tags "resistor SMD 0402")
    (property "Author" "Antmicro")
    (property "License" "Apache-2.0")
    (property "MPN" "CR0402-FX-1004GLF")
    (property "Manufacturer" "Bourns")
    (property "Sheetfile" "dp.kicad_sch")
    (property "Sheetname" "Display Port")
    (property "Tolerance" "1%")
    (property "Val" "1M")
    (property "ki_description" "1M resistor in 0402 package with 1% tolerance")
    (attr smd)
    (fp_text reference "R12" (at -1.05 -2.41 90) (layer "F.SilkS")
        (effects (font (size 0.7 0.7) (thickness 0.15)) (justify left bottom))
    )
    (fp_text value "R_1M_0402" (at 0 1.4 90) (layer "F.Fab") hide
        (effects (font (size 0.7 0.7) (thickness 0.15)) (justify left bottom))
    )
    (fp_text user "License: Apache-2.0" (at -0.95 5.169 90) (layer "F.Fab") hide
        (effects (font (size 0.7 0.7) (thickness 0.15)) (justify left bottom))
    )
    (fp_text user "${REFERENCE}" (at -0.95 3.168 90) (layer "F.Fab") hide
        (effects (font (size 0.7 0.7) (thickness 0.15)) (justify left bottom))
    )
    (fp_text user "Author: Antmicro" (at -0.95 4.169 90) (layer "F.Fab") hide
        (effects (font (size 0.7 0.7) (thickness 0.15)) (justify left bottom))
    )
    (fp_rect (start -0.93 -0.47) (end 0.93 0.47)
      (stroke (width 0.05) (type solid)) (fill none) (layer "F.CrtYd"))
    (fp_rect (start -0.5 -0.25) (end 0.5 0.25)
      (stroke (width 0.15) (type solid)) (fill none) (layer "F.Fab"))
    (pad "1" smd roundrect (at -0.485 0 90) (size 0.59 0.64) (layers "F.Cu" "F.Paste" "F.Mask") (roundrect_rratio 0.25)
      (net 1 "GND") (pintype "passive"))
    (pad "2" smd roundrect (at 0.485 0 90) (size 0.59 0.64) (layers "F.Cu" "F.Paste" "F.Mask") (roundrect_rratio 0.25)
      (net 349 "Net-(J1-CFG2)") (pintype "passive"))
  )
)
